# S9S_MB_2U (Grand Teton) — schematic netlist excerpt (pin names and nets, part order shuffled) for the footprints in the layout excerpt that follows; sources: Cadence DE-HDL packaged netlist, KiCad conversion of 03242023_DA0F0TMBIJ0_F0T_Motherboard_J_brd_V01_OCP.brd

ME22  ME_DUMMY_SYMBOL  SNLABEL_27X6 EMPTY  pkg SNLABEL_27X6  page 312
PR591  Q_RES  100 1% CHIP  pkg 0402LF  page 278 : A = VSENSE_PVCCD_HV_CPU0_DN ; B = GND
R3621  Q_RES  4.7K 1% EMPTY  pkg 0402LF  page 172 : A = P3V3_AUX ; B = INA230_4_A0

(kicad_pcb
	(version 20260206)
	(generator "pcbnew")
	(generator_version "10.0")
	(general
		(thickness 1.6)
		(legacy_teardrops no)
	)
	(paper "A4")
	(title_block
		(title "03242023_DA0F0TMBIJ0_F0T_Motherboard_J_brd_V01_OCP.brd")
		(comment 1 "Grand Teton / footprints 1408-1410 of 6105")
	)
	(layers
		(0 "F.Cu" signal "TOP")
		(4 "In1.Cu" signal "GND")
		(6 "In2.Cu" signal "IN1")
		(8 "In3.Cu" signal "GND1")
		(10 "In4.Cu" signal "IN2")
		(12 "In5.Cu" signal "GND2")
		(14 "In6.Cu" signal "IN3")
		(16 "In7.Cu" signal "GND3")
		(18 "In8.Cu" signal "VCC")
		(20 "In9.Cu" signal "VCC1")
		(22 "In10.Cu" signal "GND4")
		(24 "In11.Cu" signal "IN4")
		(26 "In12.Cu" signal "GND5")
		(28 "In13.Cu" signal "IN5")
		(30 "In14.Cu" signal "GND6")
		(32 "In15.Cu" signal "IN6")
		(34 "In16.Cu" signal "GND7")
		(2 "B.Cu" signal "BOTTOM")
		(9 "F.Adhes" user "F.Adhesive")
		(11 "B.Adhes" user "B.Adhesive")
		(13 "F.Paste" user "Package Geometry/Pastemask Top")
		(15 "B.Paste" user "Package Geometry/Pastemask Bottom")
		(5 "F.SilkS" user "Ref Des/Silkscreen Top")
		(7 "B.SilkS" user "Ref Des/Silkscreen Bottom")
		(1 "F.Mask" user "Board Geometry/Soldermask Top")
		(3 "B.Mask" user "Board Geometry/Soldermask Bottom")
		(17 "Dwgs.User" user "User.Drawings")
		(19 "Cmts.User" user "User.Comments")
		(21 "Eco1.User" user "User.Eco1")
		(23 "Eco2.User" user "User.Eco2")
		(25 "Edge.Cuts" user "Board Geometry/Outline")
		(27 "Margin" user)
		(31 "F.CrtYd" user "Package Geometry/Place Bound Top")
		(29 "B.CrtYd" user "Package Geometry/Place Bound Bottom")
		(35 "F.Fab" user "Ref Des/Assembly Top")
		(33 "B.Fab" user "Ref Des/Assembly Bottom")
	)
	(footprint ""
		(layer "F.Cu")
		(at 148.197824 -50.388012)
		(property "Reference" "R3621"
			(at 0 0 0)
			(layer "F.SilkS")
			(hide yes)
			(effects
				(font
					(size 1.27 1.27)
				)
			)
		)
		(property "Value" ""
			(at 0 0 0)
			(layer "F.Fab")
			(effects
				(font
					(size 1.27 1.27)
				)
			)
		)
		(duplicate_pad_numbers_are_jumpers no)
		(fp_line
			(start -0.7874 -0.4064)
			(end 0.7874 -0.4064)
			(stroke
				(width 0.1524)
				(type default)
			)
			(layer "F.SilkS")
		)
		(fp_line
			(start -0.7874 0.4064)
			(end -0.7874 -0.4064)
			(stroke
				(width 0.1524)
				(type default)
			)
			(layer "F.SilkS")
		)
		(fp_line
			(start 0.7874 -0.4064)
			(end 0.7874 0.4064)
			(stroke
				(width 0.1524)
				(type default)
			)
			(layer "F.SilkS")
		)
		(fp_line
			(start 0.7874 0.4064)
			(end -0.7874 0.4064)
			(stroke
				(width 0.1524)
				(type default)
			)
			(layer "F.SilkS")
		)
		(fp_line
			(start -0.67945 -0.305054)
			(end -0.12065 -0.305054)
			(stroke
				(width 0.1)
				(type default)
			)
			(layer "F.Fab")
		)
		(fp_line
			(start -0.67945 0.3048)
			(end -0.67945 -0.305054)
			(stroke
				(width 0.1)
				(type default)
			)
			(layer "F.Fab")
		)
		(fp_line
			(start -0.12065 -0.305054)
			(end -0.12065 -0.2794)
			(stroke
				(width 0.1)
				(type default)
			)
			(layer "F.Fab")
		)
		(fp_line
			(start -0.12065 -0.2794)
			(end 0.12065 -0.2794)
			(stroke
				(width 0.1)
				(type default)
			)
			(layer "F.Fab")
		)
		(fp_line
			(start -0.12065 0.2794)
			(end -0.12065 0.3048)
			(stroke
				(width 0.1)
				(type default)
			)
			(layer "F.Fab")
		)
		(fp_line
			(start -0.12065 0.3048)
			(end -0.67945 0.3048)
			(stroke
				(width 0.1)
				(type default)
			)
			(layer "F.Fab")
		)
		(fp_line
			(start 0.120396 0.2794)
			(end -0.12065 0.2794)
			(stroke
				(width 0.1)
				(type default)
			)
			(layer "F.Fab")
		)
		(fp_line
			(start 0.120396 0.3048)
			(end 0.120396 0.2794)
			(stroke
				(width 0.1)
				(type default)
			)
			(layer "F.Fab")
		)
		(fp_line
			(start 0.12065 -0.3048)
			(end 0.67945 -0.3048)
			(stroke
				(width 0.1)
				(type default)
			)
			(layer "F.Fab")
		)
		(fp_line
			(start 0.12065 -0.2794)
			(end 0.12065 -0.3048)
			(stroke
				(width 0.1)
				(type default)
			)
			(layer "F.Fab")
		)
		(fp_line
			(start 0.67945 -0.3048)
			(end 0.67945 0.3048)
			(stroke
				(width 0.1)
				(type default)
			)
			(layer "F.Fab")
		)
		(fp_line
			(start 0.67945 0.3048)
			(end 0.120396 0.3048)
			(stroke
				(width 0.1)
				(type default)
			)
			(layer "F.Fab")
		)
		(pad "1" smd circle
			(at -0.40005 0)
			(size 0 0)
			(layers "F.Cu" "F.Mask" "F.Paste")
			(net "P3V3_AUX")
		)
		(pad "2" smd circle
			(at 0.40005 0)
			(size 0 0)
			(layers "F.Cu" "F.Mask" "F.Paste")
			(net "INA230_4_A0")
		)
	)
	(footprint ""
		(layer "F.Cu")
		(at 224.16262 -378.176028)
		(property "Reference" "ME22"
			(at -0.1016 -6.949948 0)
			(unlocked yes)
			(layer "F.SilkS")
			(effects
				(font
					(size 0.7874 0.5842)
					(thickness 0.1524)
				)
				(justify left)
			)
		)
		(property "Value" ""
			(at 0 0 0)
			(layer "F.Fab")
			(effects
				(font
					(size 1.27 1.27)
				)
			)
		)
		(duplicate_pad_numbers_are_jumpers no)
		(fp_line
			(start 0 -5.999988)
			(end 0 -4.475988)
			(stroke
				(width 0.1524)
				(type default)
			)
			(layer "F.SilkS")
		)
		(fp_line
			(start 0 -1.524)
			(end 0 0)
			(stroke
				(width 0.1524)
				(type default)
			)
			(layer "F.SilkS")
		)
		(fp_line
			(start 0 0)
			(end 1.524 0)
			(stroke
				(width 0.1524)
				(type default)
			)
			(layer "F.SilkS")
		)
		(fp_line
			(start 1.524 -5.999988)
			(end 0 -5.999988)
			(stroke
				(width 0.1524)
				(type default)
			)
			(layer "F.SilkS")
		)
		(fp_line
			(start 25.475946 -5.999988)
			(end 26.999946 -5.999988)
			(stroke
				(width 0.1524)
				(type default)
			)
			(layer "F.SilkS")
		)
		(fp_line
			(start 26.999946 -5.999988)
			(end 26.999946 -4.475988)
			(stroke
				(width 0.1524)
				(type default)
			)
			(layer "F.SilkS")
		)
		(fp_line
			(start 26.999946 -1.524)
			(end 26.999946 0)
			(stroke
				(width 0.1524)
				(type default)
			)
			(layer "F.SilkS")
		)
		(fp_line
			(start 26.999946 0)
			(end 25.475946 0)
			(stroke
				(width 0.1524)
				(type default)
			)
			(layer "F.SilkS")
		)
		(fp_text user "S/N"
			(at 0.2032 -4.59105 0)
			(unlocked yes)
			(layer "F.SilkS")
			(effects
				(font
					(size 1.905 1.4224)
					(thickness 0.1524)
				)
				(justify left)
			)
		)
	)
	(footprint ""
		(layer "F.Cu")
		(at 397.403066 -167.491664)
		(property "Reference" "PR591"
			(at 0 0 0)
			(layer "F.SilkS")
			(hide yes)
			(effects
				(font
					(size 1.27 1.27)
				)
			)
		)
		(property "Value" ""
			(at 0 0 0)
			(layer "F.Fab")
			(effects
				(font
					(size 1.27 1.27)
				)
			)
		)
		(duplicate_pad_numbers_are_jumpers no)
		(fp_line
			(start -0.7874 -0.4064)
			(end 0.7874 -0.4064)
			(stroke
				(width 0.1524)
				(type default)
			)
			(layer "F.SilkS")
		)
		(fp_line
			(start -0.7874 0.4064)
			(end -0.7874 -0.4064)
			(stroke
				(width 0.1524)
				(type default)
			)
			(layer "F.SilkS")
		)
		(fp_line
			(start 0.7874 -0.4064)
			(end 0.7874 0.4064)
			(stroke
				(width 0.1524)
				(type default)
			)
			(layer "F.SilkS")
		)
		(fp_line
			(start 0.7874 0.4064)
			(end -0.7874 0.4064)
			(stroke
				(width 0.1524)
				(type default)
			)
			(layer "F.SilkS")
		)
		(fp_line
			(start -0.67945 -0.305054)
			(end -0.12065 -0.305054)
			(stroke
				(width 0.1)
				(type default)
			)
			(layer "F.Fab")
		)
		(fp_line
			(start -0.67945 0.3048)
			(end -0.67945 -0.305054)
			(stroke
				(width 0.1)
				(type default)
			)
			(layer "F.Fab")
		)
		(fp_line
			(start -0.12065 -0.305054)
			(end -0.12065 -0.2794)
			(stroke
				(width 0.1)
				(type default)
			)
			(layer "F.Fab")
		)
		(fp_line
			(start -0.12065 -0.2794)
			(end 0.12065 -0.2794)
			(stroke
				(width 0.1)
				(type default)
			)
			(layer "F.Fab")
		)
		(fp_line
			(start -0.12065 0.2794)
			(end -0.12065 0.3048)
			(stroke
				(width 0.1)
				(type default)
			)
			(layer "F.Fab")
		)
		(fp_line
			(start -0.12065 0.3048)
			(end -0.67945 0.3048)
			(stroke
				(width 0.1)
				(type default)
			)
			(layer "F.Fab")
		)
		(fp_line
			(start 0.120396 0.2794)
			(end -0.12065 0.2794)
			(stroke
				(width 0.1)
				(type default)
			)
			(layer "F.Fab")
		)
		(fp_line
			(start 0.120396 0.3048)
			(end 0.120396 0.2794)
			(stroke
				(width 0.1)
				(type default)
			)
			(layer "F.Fab")
		)
		(fp_line
			(start 0.12065 -0.3048)
			(end 0.67945 -0.3048)
			(stroke
				(width 0.1)
				(type default)
			)
			(layer "F.Fab")
		)
		(fp_line
			(start 0.12065 -0.2794)
			(end 0.12065 -0.3048)
			(stroke
				(width 0.1)
				(type default)
			)
			(layer "F.Fab")
		)
		(fp_line
			(start 0.67945 -0.3048)
			(end 0.67945 0.3048)
			(stroke
				(width 0.1)
				(type default)
			)
			(layer "F.Fab")
		)
		(fp_line
			(start 0.67945 0.3048)
			(end 0.120396 0.3048)
			(stroke
				(width 0.1)
				(type default)
			)
			(layer "F.Fab")
		)
		(pad "1" smd circle
			(at -0.40005 0)
			(size 0 0)
			(layers "F.Cu" "F.Mask" "F.Paste")
			(net "VSENSE_PVCCD_HV_CPU0_DN")
		)
		(pad "2" smd circle
			(at 0.40005 0)
			(size 0 0)
			(layers "F.Cu" "F.Mask" "F.Paste")
			(net "GND")
		)
	)
)
